(kicad_pcb
	(version 20260206)
	(generator "pcbnew")
	(generator_version "10.0")
	(general
		(thickness 1.6)
		(legacy_teardrops no)
	)
	(paper "A4")
	(title_block
		(title "03242023_DA0F0TMBIJ0_F0T_Motherboard_J_brd_V01_OCP.brd")
		(comment 1 "Grand Teton / footprints 2887-2893 of 6105")
	)
	(layers
		(0 "F.Cu" signal "TOP")
		(4 "In1.Cu" signal "GND")
		(6 "In2.Cu" signal "IN1")
		(8 "In3.Cu" signal "GND1")
		(10 "In4.Cu" signal "IN2")
		(12 "In5.Cu" signal "GND2")
		(14 "In6.Cu" signal "IN3")
		(16 "In7.Cu" signal "GND3")
		(18 "In8.Cu" signal "VCC")
		(20 "In9.Cu" signal "VCC1")
		(22 "In10.Cu" signal "GND4")
		(24 "In11.Cu" signal "IN4")
		(26 "In12.Cu" signal "GND5")
		(28 "In13.Cu" signal "IN5")
		(30 "In14.Cu" signal "GND6")
		(32 "In15.Cu" signal "IN6")
		(34 "In16.Cu" signal "GND7")
		(2 "B.Cu" signal "BOTTOM")
		(9 "F.Adhes" user "F.Adhesive")
		(11 "B.Adhes" user "B.Adhesive")
		(13 "F.Paste" user "Package Geometry/Pastemask Top")
		(15 "B.Paste" user "Package Geometry/Pastemask Bottom")
		(5 "F.SilkS" user "Ref Des/Silkscreen Top")
		(7 "B.SilkS" user "Ref Des/Silkscreen Bottom")
		(1 "F.Mask" user "Board Geometry/Soldermask Top")
		(3 "B.Mask" user "Board Geometry/Soldermask Bottom")
		(17 "Dwgs.User" user "User.Drawings")
		(19 "Cmts.User" user "User.Comments")
		(21 "Eco1.User" user "User.Eco1")
		(23 "Eco2.User" user "User.Eco2")
		(25 "Edge.Cuts" user "Board Geometry/Outline")
		(27 "Margin" user)
		(31 "F.CrtYd" user "Package Geometry/Place Bound Top")
		(29 "B.CrtYd" user "Package Geometry/Place Bound Bottom")
		(35 "F.Fab" user "Ref Des/Assembly Top")
		(33 "B.Fab" user "Ref Des/Assembly Bottom")
	)
	(footprint ""
		(layer "F.Cu")
		(at 363.64672 -403.322028)
		(property "Reference" "U204"
			(at -0.13208 1.83261 0)
			(unlocked yes)
			(layer "F.SilkS")
			(effects
				(font
					(size 0.7874 0.5842)
					(thickness 0.1524)
				)
				(justify left)
			)
		)
		(property "Value" ""
			(at 0 0 0)
			(layer "F.Fab")
			(effects
				(font
					(size 1.27 1.27)
				)
			)
		)
		(duplicate_pad_numbers_are_jumpers no)
		(fp_line
			(start -1.400048 1.100074)
			(end -1.400048 -1.100074)
			(stroke
				(width 0.1524)
				(type default)
			)
			(layer "F.SilkS")
		)
		(fp_line
			(start 1.400048 -1.100074)
			(end -1.400048 -1.100074)
			(stroke
				(width 0.1524)
				(type default)
			)
			(layer "F.SilkS")
		)
		(fp_line
			(start 1.400048 -1.100074)
			(end 1.400048 1.100074)
			(stroke
				(width 0.1524)
				(type default)
			)
			(layer "F.SilkS")
		)
		(fp_line
			(start 1.400048 1.100074)
			(end -1.400048 1.100074)
			(stroke
				(width 0.1524)
				(type default)
			)
			(layer "F.SilkS")
		)
		(fp_poly
			(pts
				(xy -0.95631 -1.391412) (xy -1.46431 -2.407412) (xy -0.44831 -2.407412)
			)
			(stroke
				(width 0)
				(type default)
			)
			(fill yes)
			(layer "F.SilkS")
		)
		(fp_line
			(start -0.674878 -1.100074)
			(end 0.674878 -1.100074)
			(stroke
				(width 0.1)
				(type default)
			)
			(layer "F.Fab")
		)
		(fp_line
			(start -0.674878 1.100074)
			(end -0.674878 -1.100074)
			(stroke
				(width 0.1)
				(type default)
			)
			(layer "F.Fab")
		)
		(fp_line
			(start 0.674878 -1.100074)
			(end 0.674878 1.100074)
			(stroke
				(width 0.1)
				(type default)
			)
			(layer "F.Fab")
		)
		(fp_line
			(start 0.674878 1.100074)
			(end -0.674878 1.100074)
			(stroke
				(width 0.1)
				(type default)
			)
			(layer "F.Fab")
		)
		(fp_poly
			(pts
				(xy -1.590548 -0.649986) (xy -2.606548 -1.157986) (xy -2.606548 -0.141986)
			)
			(stroke
				(width 0)
				(type default)
			)
			(fill yes)
			(layer "F.Fab")
		)
		(pad "1" smd rect
			(at -0.94996 -0.649986 270)
			(size 0.4318 0.6096)
			(layers "F.Cu" "F.Mask" "F.Paste")
			(net "FM_UART_EN")
		)
		(pad "2" smd rect
			(at -0.94996 0 270)
			(size 0.4318 0.6096)
			(layers "F.Cu" "F.Mask" "F.Paste")
			(net "UART_BMC_BIC_R_RX")
		)
		(pad "3" smd rect
			(at -0.94996 0.649986 270)
			(size 0.4318 0.6096)
			(layers "F.Cu" "F.Mask" "F.Paste")
			(net "GND")
		)
		(pad "4" smd rect
			(at 0.94996 0.649986 270)
			(size 0.4318 0.6096)
			(layers "F.Cu" "F.Mask" "F.Paste")
			(net "UART_BMC_BIC_R_BUF_RX")
		)
		(pad "5" smd rect
			(at 0.94996 -0.649986 270)
			(size 0.4318 0.6096)
			(layers "F.Cu" "F.Mask" "F.Paste")
			(net "P3V3_AUX")
		)
	)
	(footprint ""
		(layer "F.Cu")
		(at 466.67547 -48.940212 180)
		(property "Reference" "R1592"
			(at 0 0 180)
			(layer "F.SilkS")
			(hide yes)
			(effects
				(font
					(size 1.27 1.27)
				)
			)
		)
		(property "Value" ""
			(at 0 0 180)
			(layer "F.Fab")
			(effects
				(font
					(size 1.27 1.27)
				)
			)
		)
		(duplicate_pad_numbers_are_jumpers no)
		(fp_line
			(start 0.7874 0.4064)
			(end -0.7874 0.4064)
			(stroke
				(width 0.1524)
				(type default)
			)
			(layer "F.SilkS")
		)
		(fp_line
			(start 0.7874 -0.4064)
			(end 0.7874 0.4064)
			(stroke
				(width 0.1524)
				(type default)
			)
			(layer "F.SilkS")
		)
		(fp_line
			(start -0.7874 0.4064)
			(end -0.7874 -0.4064)
			(stroke
				(width 0.1524)
				(type default)
			)
			(layer "F.SilkS")
		)
		(fp_line
			(start -0.7874 -0.4064)
			(end 0.7874 -0.4064)
			(stroke
				(width 0.1524)
				(type default)
			)
			(layer "F.SilkS")
		)
		(fp_line
			(start 0.67945 0.3048)
			(end 0.120396 0.3048)
			(stroke
				(width 0.1)
				(type default)
			)
			(layer "F.Fab")
		)
		(fp_line
			(start 0.67945 -0.3048)
			(end 0.67945 0.3048)
			(stroke
				(width 0.1)
				(type default)
			)
			(layer "F.Fab")
		)
		(fp_line
			(start 0.12065 -0.2794)
			(end 0.12065 -0.3048)
			(stroke
				(width 0.1)
				(type default)
			)
			(layer "F.Fab")
		)
		(fp_line
			(start 0.12065 -0.3048)
			(end 0.67945 -0.3048)
			(stroke
				(width 0.1)
				(type default)
			)
			(layer "F.Fab")
		)
		(fp_line
			(start 0.120396 0.3048)
			(end 0.120396 0.2794)
			(stroke
				(width 0.1)
				(type default)
			)
			(layer "F.Fab")
		)
		(fp_line
			(start 0.120396 0.2794)
			(end -0.12065 0.2794)
			(stroke
				(width 0.1)
				(type default)
			)
			(layer "F.Fab")
		)
		(fp_line
			(start -0.12065 0.3048)
			(end -0.67945 0.3048)
			(stroke
				(width 0.1)
				(type default)
			)
			(layer "F.Fab")
		)
		(fp_line
			(start -0.12065 0.2794)
			(end -0.12065 0.3048)
			(stroke
				(width 0.1)
				(type default)
			)
			(layer "F.Fab")
		)
		(fp_line
			(start -0.12065 -0.2794)
			(end 0.12065 -0.2794)
			(stroke
				(width 0.1)
				(type default)
			)
			(layer "F.Fab")
		)
		(fp_line
			(start -0.12065 -0.305054)
			(end -0.12065 -0.2794)
			(stroke
				(width 0.1)
				(type default)
			)
			(layer "F.Fab")
		)
		(fp_line
			(start -0.67945 0.3048)
			(end -0.67945 -0.305054)
			(stroke
				(width 0.1)
				(type default)
			)
			(layer "F.Fab")
		)
		(fp_line
			(start -0.67945 -0.305054)
			(end -0.12065 -0.305054)
			(stroke
				(width 0.1)
				(type default)
			)
			(layer "F.Fab")
		)
		(pad "1" smd circle
			(at -0.40005 0 180)
			(size 0 0)
			(layers "F.Cu" "F.Mask" "F.Paste")
			(net "P3V3_OCP_SFF")
		)
		(pad "2" smd circle
			(at 0.40005 0 180)
			(size 0 0)
			(layers "F.Cu" "F.Mask" "F.Paste")
			(net "PU_OCP_SFF_WAKE_OE")
		)
	)
	(footprint ""
		(layer "F.Cu")
		(at 46.626018 -440.205368 180)
		(property "Reference" "R3107"
			(at 0 0 180)
			(layer "F.SilkS")
			(hide yes)
			(effects
				(font
					(size 1.27 1.27)
				)
			)
		)
		(property "Value" ""
			(at 0 0 180)
			(layer "F.Fab")
			(effects
				(font
					(size 1.27 1.27)
				)
			)
		)
		(duplicate_pad_numbers_are_jumpers no)
		(fp_line
			(start 0.7874 0.4064)
			(end -0.7874 0.4064)
			(stroke
				(width 0.1524)
				(type default)
			)
			(layer "F.SilkS")
		)
		(fp_line
			(start 0.7874 -0.4064)
			(end 0.7874 0.4064)
			(stroke
				(width 0.1524)
				(type default)
			)
			(layer "F.SilkS")
		)
		(fp_line
			(start -0.7874 0.4064)
			(end -0.7874 -0.4064)
			(stroke
				(width 0.1524)
				(type default)
			)
			(layer "F.SilkS")
		)
		(fp_line
			(start -0.7874 -0.4064)
			(end 0.7874 -0.4064)
			(stroke
				(width 0.1524)
				(type default)
			)
			(layer "F.SilkS")
		)
		(fp_line
			(start 0.67945 0.3048)
			(end 0.120396 0.3048)
			(stroke
				(width 0.1)
				(type default)
			)
			(layer "F.Fab")
		)
		(fp_line
			(start 0.67945 -0.3048)
			(end 0.67945 0.3048)
			(stroke
				(width 0.1)
				(type default)
			)
			(layer "F.Fab")
		)
		(fp_line
			(start 0.12065 -0.2794)
			(end 0.12065 -0.3048)
			(stroke
				(width 0.1)
				(type default)
			)
			(layer "F.Fab")
		)
		(fp_line
			(start 0.12065 -0.3048)
			(end 0.67945 -0.3048)
			(stroke
				(width 0.1)
				(type default)
			)
			(layer "F.Fab")
		)
		(fp_line
			(start 0.120396 0.3048)
			(end 0.120396 0.2794)
			(stroke
				(width 0.1)
				(type default)
			)
			(layer "F.Fab")
		)
		(fp_line
			(start 0.120396 0.2794)
			(end -0.12065 0.2794)
			(stroke
				(width 0.1)
				(type default)
			)
			(layer "F.Fab")
		)
		(fp_line
			(start -0.12065 0.3048)
			(end -0.67945 0.3048)
			(stroke
				(width 0.1)
				(type default)
			)
			(layer "F.Fab")
		)
		(fp_line
			(start -0.12065 0.2794)
			(end -0.12065 0.3048)
			(stroke
				(width 0.1)
				(type default)
			)
			(layer "F.Fab")
		)
		(fp_line
			(start -0.12065 -0.2794)
			(end 0.12065 -0.2794)
			(stroke
				(width 0.1)
				(type default)
			)
			(layer "F.Fab")
		)
		(fp_line
			(start -0.12065 -0.305054)
			(end -0.12065 -0.2794)
			(stroke
				(width 0.1)
				(type default)
			)
			(layer "F.Fab")
		)
		(fp_line
			(start -0.67945 0.3048)
			(end -0.67945 -0.305054)
			(stroke
				(width 0.1)
				(type default)
			)
			(layer "F.Fab")
		)
		(fp_line
			(start -0.67945 -0.305054)
			(end -0.12065 -0.305054)
			(stroke
				(width 0.1)
				(type default)
			)
			(layer "F.Fab")
		)
		(pad "1" smd circle
			(at -0.40005 0 180)
			(size 0 0)
			(layers "F.Cu" "F.Mask" "F.Paste")
			(net "SMB_2_BMC_GPU_SCL")
		)
		(pad "2" smd circle
			(at 0.40005 0 180)
			(size 0 0)
			(layers "F.Cu" "F.Mask" "F.Paste")
			(net "SMB_2_BMC_GPU_R_SCL")
		)
	)
	(footprint ""
		(layer "F.Cu")
		(at 46.626018 -439.189368 180)
		(property "Reference" "R3521"
			(at 0 0 180)
			(layer "F.SilkS")
			(hide yes)
			(effects
				(font
					(size 1.27 1.27)
				)
			)
		)
		(property "Value" ""
			(at 0 0 180)
			(layer "F.Fab")
			(effects
				(font
					(size 1.27 1.27)
				)
			)
		)
		(duplicate_pad_numbers_are_jumpers no)
		(fp_line
			(start 0.7874 0.4064)
			(end -0.7874 0.4064)
			(stroke
				(width 0.1524)
				(type default)
			)
			(layer "F.SilkS")
		)
		(fp_line
			(start 0.7874 -0.4064)
			(end 0.7874 0.4064)
			(stroke
				(width 0.1524)
				(type default)
			)
			(layer "F.SilkS")
		)
		(fp_line
			(start -0.7874 0.4064)
			(end -0.7874 -0.4064)
			(stroke
				(width 0.1524)
				(type default)
			)
			(layer "F.SilkS")
		)
		(fp_line
			(start -0.7874 -0.4064)
			(end 0.7874 -0.4064)
			(stroke
				(width 0.1524)
				(type default)
			)
			(layer "F.SilkS")
		)
		(fp_line
			(start 0.67945 0.3048)
			(end 0.120396 0.3048)
			(stroke
				(width 0.1)
				(type default)
			)
			(layer "F.Fab")
		)
		(fp_line
			(start 0.67945 -0.3048)
			(end 0.67945 0.3048)
			(stroke
				(width 0.1)
				(type default)
			)
			(layer "F.Fab")
		)
		(fp_line
			(start 0.12065 -0.2794)
			(end 0.12065 -0.3048)
			(stroke
				(width 0.1)
				(type default)
			)
			(layer "F.Fab")
		)
		(fp_line
			(start 0.12065 -0.3048)
			(end 0.67945 -0.3048)
			(stroke
				(width 0.1)
				(type default)
			)
			(layer "F.Fab")
		)
		(fp_line
			(start 0.120396 0.3048)
			(end 0.120396 0.2794)
			(stroke
				(width 0.1)
				(type default)
			)
			(layer "F.Fab")
		)
		(fp_line
			(start 0.120396 0.2794)
			(end -0.12065 0.2794)
			(stroke
				(width 0.1)
				(type default)
			)
			(layer "F.Fab")
		)
		(fp_line
			(start -0.12065 0.3048)
			(end -0.67945 0.3048)
			(stroke
				(width 0.1)
				(type default)
			)
			(layer "F.Fab")
		)
		(fp_line
			(start -0.12065 0.2794)
			(end -0.12065 0.3048)
			(stroke
				(width 0.1)
				(type default)
			)
			(layer "F.Fab")
		)
		(fp_line
			(start -0.12065 -0.2794)
			(end 0.12065 -0.2794)
			(stroke
				(width 0.1)
				(type default)
			)
			(layer "F.Fab")
		)
		(fp_line
			(start -0.12065 -0.305054)
			(end -0.12065 -0.2794)
			(stroke
				(width 0.1)
				(type default)
			)
			(layer "F.Fab")
		)
		(fp_line
			(start -0.67945 0.3048)
			(end -0.67945 -0.305054)
			(stroke
				(width 0.1)
				(type default)
			)
			(layer "F.Fab")
		)
		(fp_line
			(start -0.67945 -0.305054)
			(end -0.12065 -0.305054)
			(stroke
				(width 0.1)
				(type default)
			)
			(layer "F.Fab")
		)
		(pad "1" smd circle
			(at -0.40005 0 180)
			(size 0 0)
			(layers "F.Cu" "F.Mask" "F.Paste")
			(net "P3V3_AUX")
		)
		(pad "2" smd circle
			(at 0.40005 0 180)
			(size 0 0)
			(layers "F.Cu" "F.Mask" "F.Paste")
			(net "SMB_2_BMC_GPU_BUF_R_SCL")
		)
	)
	(footprint ""
		(layer "F.Cu")
		(at 208.49336 -121.1072 180)
		(property "Reference" "C2370"
			(at 0 0 180)
			(layer "F.SilkS")
			(hide yes)
			(effects
				(font
					(size 1.27 1.27)
				)
			)
		)
		(property "Value" ""
			(at 0 0 180)
			(layer "F.Fab")
			(effects
				(font
					(size 1.27 1.27)
				)
			)
		)
		(duplicate_pad_numbers_are_jumpers no)
		(fp_line
			(start 0.7874 0.4064)
			(end -0.7874 0.4064)
			(stroke
				(width 0.1524)
				(type default)
			)
			(layer "F.SilkS")
		)
		(fp_line
			(start 0.7874 -0.4064)
			(end 0.7874 0.4064)
			(stroke
				(width 0.1524)
				(type default)
			)
			(layer "F.SilkS")
		)
		(fp_line
			(start -0.7874 0.4064)
			(end -0.7874 -0.4064)
			(stroke
				(width 0.1524)
				(type default)
			)
			(layer "F.SilkS")
		)
		(fp_line
			(start -0.7874 -0.4064)
			(end 0.7874 -0.4064)
			(stroke
				(width 0.1524)
				(type default)
			)
			(layer "F.SilkS")
		)
		(fp_line
			(start 0.67945 0.3048)
			(end 0.120396 0.3048)
			(stroke
				(width 0.1)
				(type default)
			)
			(layer "F.Fab")
		)
		(fp_line
			(start 0.67945 -0.3048)
			(end 0.67945 0.3048)
			(stroke
				(width 0.1)
				(type default)
			)
			(layer "F.Fab")
		)
		(fp_line
			(start 0.12065 -0.2794)
			(end 0.12065 -0.3048)
			(stroke
				(width 0.1)
				(type default)
			)
			(layer "F.Fab")
		)
		(fp_line
			(start 0.12065 -0.3048)
			(end 0.67945 -0.3048)
			(stroke
				(width 0.1)
				(type default)
			)
			(layer "F.Fab")
		)
		(fp_line
			(start 0.120396 0.3048)
			(end 0.120396 0.2794)
			(stroke
				(width 0.1)
				(type default)
			)
			(layer "F.Fab")
		)
		(fp_line
			(start 0.120396 0.2794)
			(end -0.12065 0.2794)
			(stroke
				(width 0.1)
				(type default)
			)
			(layer "F.Fab")
		)
		(fp_line
			(start -0.12065 0.3048)
			(end -0.67945 0.3048)
			(stroke
				(width 0.1)
				(type default)
			)
			(layer "F.Fab")
		)
		(fp_line
			(start -0.12065 0.2794)
			(end -0.12065 0.3048)
			(stroke
				(width 0.1)
				(type default)
			)
			(layer "F.Fab")
		)
		(fp_line
			(start -0.12065 -0.2794)
			(end 0.12065 -0.2794)
			(stroke
				(width 0.1)
				(type default)
			)
			(layer "F.Fab")
		)
		(fp_line
			(start -0.12065 -0.305054)
			(end -0.12065 -0.2794)
			(stroke
				(width 0.1)
				(type default)
			)
			(layer "F.Fab")
		)
		(fp_line
			(start -0.67945 0.3048)
			(end -0.67945 -0.305054)
			(stroke
				(width 0.1)
				(type default)
			)
			(layer "F.Fab")
		)
		(fp_line
			(start -0.67945 -0.305054)
			(end -0.12065 -0.305054)
			(stroke
				(width 0.1)
				(type default)
			)
			(layer "F.Fab")
		)
		(pad "1" smd circle
			(at -0.40005 0 180)
			(size 0 0)
			(layers "F.Cu" "F.Mask" "F.Paste")
			(net "P3V3_AUX")
		)
		(pad "2" smd circle
			(at 0.40005 0 180)
			(size 0 0)
			(layers "F.Cu" "F.Mask" "F.Paste")
			(net "GND")
		)
	)
	(footprint ""
		(layer "F.Cu")
		(at 282.61818 -137.577068)
		(property "Reference" ""
			(at 0 0 0)
			(layer "F.SilkS")
			(hide yes)
			(effects
				(font
					(size 1.27 1.27)
				)
			)
		)
		(property "Value" ""
			(at 0 0 0)
			(layer "F.Fab")
			(effects
				(font
					(size 1.27 1.27)
				)
			)
		)
		(duplicate_pad_numbers_are_jumpers no)
		(pad "1" smd circle
			(at 0 0)
			(size 0.9906 0.9906)
			(layers "F.Cu" "F.Mask" "F.Paste")
			(net "Net_289")
		)
		(zone
			(layer "F.Cu")
			(hatch none 0.5)
			(connect_pads
				(clearance 0)
			)
			(min_thickness 0.25)
			(keepout
				(tracks not_allowed)
				(vias allowed)
				(pads allowed)
				(copperpour not_allowed)
				(footprints allowed)
			)
			(placement
				(enabled no)
				(sheetname "")
			)
			(fill
				(thermal_gap 0.5)
				(thermal_bridge_width 0.5)
				(island_removal_mode 0)
			)
			(polygon
				(pts
					(arc
						(start 284.24378 -137.577068)
						(mid 280.99258 -137.577068)
						(end 284.24378 -137.577068)
					)
				)
			)
		)
	)
	(footprint ""
		(layer "F.Cu")
		(at 106.70921 -415.757868 180)
		(property "Reference" "R3352"
			(at 0 0 180)
			(layer "F.SilkS")
			(hide yes)
			(effects
				(font
					(size 1.27 1.27)
				)
			)
		)
		(property "Value" ""
			(at 0 0 180)
			(layer "F.Fab")
			(effects
				(font
					(size 1.27 1.27)
				)
			)
		)
		(duplicate_pad_numbers_are_jumpers no)
		(fp_line
			(start 0.7874 0.4064)
			(end -0.7874 0.4064)
			(stroke
				(width 0.1524)
				(type default)
			)
			(layer "F.SilkS")
		)
		(fp_line
			(start 0.7874 -0.1397)
			(end 0.7874 0.4064)
			(stroke
				(width 0.1524)
				(type default)
			)
			(layer "F.SilkS")
		)
		(fp_line
			(start -0.44577 -0.4064)
			(end 0.47371 -0.4064)
			(stroke
				(width 0.1524)
				(type default)
			)
			(layer "F.SilkS")
		)
		(fp_line
			(start -0.7874 0.4064)
			(end -0.7874 -0.16256)
			(stroke
				(width 0.1524)
				(type default)
			)
			(layer "F.SilkS")
		)
		(fp_line
			(start 0.67945 0.3048)
			(end 0.120396 0.3048)
			(stroke
				(width 0.1)
				(type default)
			)
			(layer "F.Fab")
		)
		(fp_line
			(start 0.67945 -0.3048)
			(end 0.67945 0.3048)
			(stroke
				(width 0.1)
				(type default)
			)
			(layer "F.Fab")
		)
		(fp_line
			(start 0.12065 -0.2794)
			(end 0.12065 -0.3048)
			(stroke
				(width 0.1)
				(type default)
			)
			(layer "F.Fab")
		)
		(fp_line
			(start 0.12065 -0.3048)
			(end 0.67945 -0.3048)
			(stroke
				(width 0.1)
				(type default)
			)
			(layer "F.Fab")
		)
		(fp_line
			(start 0.120396 0.3048)
			(end 0.120396 0.2794)
			(stroke
				(width 0.1)
				(type default)
			)
			(layer "F.Fab")
		)
		(fp_line
			(start 0.120396 0.2794)
			(end -0.12065 0.2794)
			(stroke
				(width 0.1)
				(type default)
			)
			(layer "F.Fab")
		)
		(fp_line
			(start -0.12065 0.3048)
			(end -0.67945 0.3048)
			(stroke
				(width 0.1)
				(type default)
			)
			(layer "F.Fab")
		)
		(fp_line
			(start -0.12065 0.2794)
			(end -0.12065 0.3048)
			(stroke
				(width 0.1)
				(type default)
			)
			(layer "F.Fab")
		)
		(fp_line
			(start -0.12065 -0.2794)
			(end 0.12065 -0.2794)
			(stroke
				(width 0.1)
				(type default)
			)
			(layer "F.Fab")
		)
		(fp_line
			(start -0.12065 -0.305054)
			(end -0.12065 -0.2794)
			(stroke
				(width 0.1)
				(type default)
			)
			(layer "F.Fab")
		)
		(fp_line
			(start -0.67945 0.3048)
			(end -0.67945 -0.305054)
			(stroke
				(width 0.1)
				(type default)
			)
			(layer "F.Fab")
		)
		(fp_line
			(start -0.67945 -0.305054)
			(end -0.12065 -0.305054)
			(stroke
				(width 0.1)
				(type default)
			)
			(layer "F.Fab")
		)
		(pad "1" smd circle
			(at -0.40005 0 180)
			(size 0 0)
			(layers "F.Cu" "F.Mask" "F.Paste")
			(net "CLK_100M_GPU_1_R_DP")
		)
		(pad "2" smd circle
			(at 0.40005 0 180)
			(size 0 0)
			(layers "F.Cu" "F.Mask" "F.Paste")
			(net "CLK_100M_GPU_1_DP")
		)
	)
)
